(kicad_pcb
	(version 20260206)
	(generator "pcbnew")
	(generator_version "10.0")
	(general
		(thickness 1.6)
		(legacy_teardrops no)
	)
	(paper "A4")
	(title_block
		(title "04192023_DAF0TMB3IC0_F0TG_MB_C_brd_V02_OCP.brd")
		(comment 1 "Grand Teton / footprints 4309-4315 of 8354")
	)
	(layers
		(0 "F.Cu" signal "TOP")
		(4 "In1.Cu" signal "GND")
		(6 "In2.Cu" signal "IN1")
		(8 "In3.Cu" signal "GND1")
		(10 "In4.Cu" signal "IN2")
		(12 "In5.Cu" signal "GND2")
		(14 "In6.Cu" signal "IN3")
		(16 "In7.Cu" signal "GND3")
		(18 "In8.Cu" signal "VCC")
		(20 "In9.Cu" signal "VCC1")
		(22 "In10.Cu" signal "GND4")
		(24 "In11.Cu" signal "IN4")
		(26 "In12.Cu" signal "GND5")
		(28 "In13.Cu" signal "IN5")
		(30 "In14.Cu" signal "GND6")
		(32 "In15.Cu" signal "IN6")
		(34 "In16.Cu" signal "GND7")
		(2 "B.Cu" signal "BOTTOM")
		(9 "F.Adhes" user "F.Adhesive")
		(11 "B.Adhes" user "B.Adhesive")
		(13 "F.Paste" user "Package Geometry/Pastemask Top")
		(15 "B.Paste" user "Package Geometry/Pastemask Bottom")
		(5 "F.SilkS" user "Ref Des/Silkscreen Top")
		(7 "B.SilkS" user "Ref Des/Silkscreen Bottom")
		(1 "F.Mask" user "Board Geometry/Soldermask Top")
		(3 "B.Mask" user "Board Geometry/Soldermask Bottom")
		(17 "Dwgs.User" user "User.Drawings")
		(19 "Cmts.User" user "User.Comments")
		(21 "Eco1.User" user "User.Eco1")
		(23 "Eco2.User" user "User.Eco2")
		(25 "Edge.Cuts" user "Board Geometry/Outline")
		(27 "Margin" user)
		(31 "F.CrtYd" user "Package Geometry/Place Bound Top")
		(29 "B.CrtYd" user "Package Geometry/Place Bound Bottom")
		(35 "F.Fab" user "Ref Des/Assembly Top")
		(33 "B.Fab" user "Ref Des/Assembly Bottom")
	)
	(footprint ""
		(layer "F.Cu")
		(at 380.618492 -381.41783 -90)
		(property "Reference" "C884"
			(at 0 0 270)
			(layer "F.SilkS")
			(hide yes)
			(effects
				(font
					(size 1.27 1.27)
				)
			)
		)
		(property "Value" ""
			(at 0 0 270)
			(layer "F.Fab")
			(effects
				(font
					(size 1.27 1.27)
				)
			)
		)
		(duplicate_pad_numbers_are_jumpers no)
		(fp_line
			(start -0.299974 0.150114)
			(end -0.299974 -0.150114)
			(stroke
				(width 0.1)
				(type default)
			)
			(layer "F.Fab")
		)
		(fp_line
			(start 0.299974 0.150114)
			(end -0.299974 0.150114)
			(stroke
				(width 0.1)
				(type default)
			)
			(layer "F.Fab")
		)
		(fp_line
			(start -0.299974 -0.150114)
			(end 0.299974 -0.150114)
			(stroke
				(width 0.1)
				(type default)
			)
			(layer "F.Fab")
		)
		(fp_line
			(start 0.299974 -0.150114)
			(end 0.299974 0.150114)
			(stroke
				(width 0.1)
				(type default)
			)
			(layer "F.Fab")
		)
		(pad "1" smd rect
			(at -0.2667 0 270)
			(size 0.3048 0.381)
			(layers "F.Cu" "F.Mask" "F.Paste")
			(net "P5E_CPU0_P3_TX_C_DN<8>")
		)
		(pad "2" smd rect
			(at 0.2667 0 270)
			(size 0.3048 0.381)
			(layers "F.Cu" "F.Mask" "F.Paste")
			(net "P5E_CPU0_P3_TX_DN<8>")
		)
	)
	(footprint ""
		(layer "F.Cu")
		(at 318.539876 -70.098412 90)
		(property "Reference" "D91"
			(at -3.934714 -0.691642 90)
			(unlocked yes)
			(layer "F.SilkS")
			(effects
				(font
					(size 0.7874 0.5842)
					(thickness 0.1524)
				)
				(justify left)
			)
		)
		(property "Value" ""
			(at 0 0 90)
			(layer "F.Fab")
			(effects
				(font
					(size 1.27 1.27)
				)
			)
		)
		(duplicate_pad_numbers_are_jumpers no)
		(fp_line
			(start 1.16078 -0.4826)
			(end 1.16078 0.4826)
			(stroke
				(width 0.1524)
				(type default)
			)
			(layer "F.SilkS")
		)
		(fp_line
			(start 1.03378 -0.4826)
			(end 1.03378 0.4826)
			(stroke
				(width 0.1524)
				(type default)
			)
			(layer "F.SilkS")
		)
		(fp_line
			(start 0.90678 -0.4826)
			(end 0.90678 0.4826)
			(stroke
				(width 0.1524)
				(type default)
			)
			(layer "F.SilkS")
		)
		(fp_line
			(start -0.64008 -0.4826)
			(end 1.16078 -0.4826)
			(stroke
				(width 0.1524)
				(type default)
			)
			(layer "F.SilkS")
		)
		(fp_line
			(start -0.79248 -0.4826)
			(end 1.03378 -0.4826)
			(stroke
				(width 0.1524)
				(type default)
			)
			(layer "F.SilkS")
		)
		(fp_line
			(start -0.89408 -0.4826)
			(end 0.90678 -0.4826)
			(stroke
				(width 0.1524)
				(type default)
			)
			(layer "F.SilkS")
		)
		(fp_line
			(start 1.16078 0.4826)
			(end -0.64008 0.4826)
			(stroke
				(width 0.1524)
				(type default)
			)
			(layer "F.SilkS")
		)
		(fp_line
			(start 1.03378 0.4826)
			(end -0.79248 0.4826)
			(stroke
				(width 0.1524)
				(type default)
			)
			(layer "F.SilkS")
		)
		(fp_line
			(start 0.90678 0.4826)
			(end -0.90678 0.4826)
			(stroke
				(width 0.1524)
				(type default)
			)
			(layer "F.SilkS")
		)
		(fp_line
			(start -0.90678 0.4826)
			(end -0.90678 -0.4699)
			(stroke
				(width 0.1524)
				(type default)
			)
			(layer "F.SilkS")
		)
		(fp_line
			(start 0.499872 -0.249936)
			(end 0.499872 0.249936)
			(stroke
				(width 0.1)
				(type default)
			)
			(layer "F.Fab")
		)
		(fp_line
			(start -0.499872 -0.249936)
			(end 0.499872 -0.249936)
			(stroke
				(width 0.1)
				(type default)
			)
			(layer "F.Fab")
		)
		(fp_line
			(start 0.499872 0.249936)
			(end -0.499872 0.249936)
			(stroke
				(width 0.1)
				(type default)
			)
			(layer "F.Fab")
		)
		(fp_line
			(start -0.499872 0.249936)
			(end -0.499872 -0.249936)
			(stroke
				(width 0.1)
				(type default)
			)
			(layer "F.Fab")
		)
		(pad "A" smd rect
			(at -0.47498 0 90)
			(size 0.6096 0.7112)
			(layers "F.Cu" "F.Mask" "F.Paste")
			(net "LED_PWRGD_P1V8_AUX")
		)
		(pad "C" smd rect
			(at 0.47498 0 90)
			(size 0.6096 0.7112)
			(layers "F.Cu" "F.Mask" "F.Paste")
			(net "LED_PWRGD_P1V8_AUX_D")
		)
	)
	(footprint ""
		(layer "F.Cu")
		(at 192.037716 -57.963054 180)
		(property "Reference" "R8028"
			(at 0 0 180)
			(layer "F.SilkS")
			(hide yes)
			(effects
				(font
					(size 1.27 1.27)
				)
			)
		)
		(property "Value" ""
			(at 0 0 180)
			(layer "F.Fab")
			(effects
				(font
					(size 1.27 1.27)
				)
			)
		)
		(duplicate_pad_numbers_are_jumpers no)
		(fp_line
			(start 0.7874 0.4064)
			(end -0.7874 0.4064)
			(stroke
				(width 0.1524)
				(type default)
			)
			(layer "F.SilkS")
		)
		(fp_line
			(start 0.7874 -0.4064)
			(end 0.7874 0.4064)
			(stroke
				(width 0.1524)
				(type default)
			)
			(layer "F.SilkS")
		)
		(fp_line
			(start -0.7874 0.4064)
			(end -0.7874 -0.4064)
			(stroke
				(width 0.1524)
				(type default)
			)
			(layer "F.SilkS")
		)
		(fp_line
			(start -0.7874 -0.4064)
			(end 0.7874 -0.4064)
			(stroke
				(width 0.1524)
				(type default)
			)
			(layer "F.SilkS")
		)
		(fp_line
			(start 0.67945 0.3048)
			(end 0.120396 0.3048)
			(stroke
				(width 0.1)
				(type default)
			)
			(layer "F.Fab")
		)
		(fp_line
			(start 0.67945 -0.3048)
			(end 0.67945 0.3048)
			(stroke
				(width 0.1)
				(type default)
			)
			(layer "F.Fab")
		)
		(fp_line
			(start 0.12065 -0.2794)
			(end 0.12065 -0.3048)
			(stroke
				(width 0.1)
				(type default)
			)
			(layer "F.Fab")
		)
		(fp_line
			(start 0.12065 -0.3048)
			(end 0.67945 -0.3048)
			(stroke
				(width 0.1)
				(type default)
			)
			(layer "F.Fab")
		)
		(fp_line
			(start 0.120396 0.3048)
			(end 0.120396 0.2794)
			(stroke
				(width 0.1)
				(type default)
			)
			(layer "F.Fab")
		)
		(fp_line
			(start 0.120396 0.2794)
			(end -0.12065 0.2794)
			(stroke
				(width 0.1)
				(type default)
			)
			(layer "F.Fab")
		)
		(fp_line
			(start -0.12065 0.3048)
			(end -0.67945 0.3048)
			(stroke
				(width 0.1)
				(type default)
			)
			(layer "F.Fab")
		)
		(fp_line
			(start -0.12065 0.2794)
			(end -0.12065 0.3048)
			(stroke
				(width 0.1)
				(type default)
			)
			(layer "F.Fab")
		)
		(fp_line
			(start -0.12065 -0.2794)
			(end 0.12065 -0.2794)
			(stroke
				(width 0.1)
				(type default)
			)
			(layer "F.Fab")
		)
		(fp_line
			(start -0.12065 -0.305054)
			(end -0.12065 -0.2794)
			(stroke
				(width 0.1)
				(type default)
			)
			(layer "F.Fab")
		)
		(fp_line
			(start -0.67945 0.3048)
			(end -0.67945 -0.305054)
			(stroke
				(width 0.1)
				(type default)
			)
			(layer "F.Fab")
		)
		(fp_line
			(start -0.67945 -0.305054)
			(end -0.12065 -0.305054)
			(stroke
				(width 0.1)
				(type default)
			)
			(layer "F.Fab")
		)
		(pad "1" smd circle
			(at -0.40005 0 180)
			(size 0 0)
			(layers "F.Cu" "F.Mask" "F.Paste")
			(net "P3V3_AUX")
		)
		(pad "2" smd circle
			(at 0.40005 0 180)
			(size 0 0)
			(layers "F.Cu" "F.Mask" "F.Paste")
			(net "LED_P12V_SCM_FAULT_D1")
		)
	)
	(footprint ""
		(layer "F.Cu")
		(at 391.082022 -137.061702 -90)
		(property "Reference" "R702"
			(at 0 0 270)
			(layer "F.SilkS")
			(hide yes)
			(effects
				(font
					(size 1.27 1.27)
				)
			)
		)
		(property "Value" ""
			(at 0 0 270)
			(layer "F.Fab")
			(effects
				(font
					(size 1.27 1.27)
				)
			)
		)
		(duplicate_pad_numbers_are_jumpers no)
		(fp_line
			(start -0.7874 0.4064)
			(end -0.7874 -0.4064)
			(stroke
				(width 0.1524)
				(type default)
			)
			(layer "F.SilkS")
		)
		(fp_line
			(start 0.7874 0.4064)
			(end -0.7874 0.4064)
			(stroke
				(width 0.1524)
				(type default)
			)
			(layer "F.SilkS")
		)
		(fp_line
			(start -0.7874 -0.4064)
			(end 0.7874 -0.4064)
			(stroke
				(width 0.1524)
				(type default)
			)
			(layer "F.SilkS")
		)
		(fp_line
			(start 0.7874 -0.4064)
			(end 0.7874 0.4064)
			(stroke
				(width 0.1524)
				(type default)
			)
			(layer "F.SilkS")
		)
		(fp_line
			(start -0.67945 0.3048)
			(end -0.67945 -0.305054)
			(stroke
				(width 0.1)
				(type default)
			)
			(layer "F.Fab")
		)
		(fp_line
			(start -0.12065 0.3048)
			(end -0.67945 0.3048)
			(stroke
				(width 0.1)
				(type default)
			)
			(layer "F.Fab")
		)
		(fp_line
			(start 0.120396 0.3048)
			(end 0.120396 0.2794)
			(stroke
				(width 0.1)
				(type default)
			)
			(layer "F.Fab")
		)
		(fp_line
			(start 0.67945 0.3048)
			(end 0.120396 0.3048)
			(stroke
				(width 0.1)
				(type default)
			)
			(layer "F.Fab")
		)
		(fp_line
			(start -0.12065 0.2794)
			(end -0.12065 0.3048)
			(stroke
				(width 0.1)
				(type default)
			)
			(layer "F.Fab")
		)
		(fp_line
			(start 0.120396 0.2794)
			(end -0.12065 0.2794)
			(stroke
				(width 0.1)
				(type default)
			)
			(layer "F.Fab")
		)
		(fp_line
			(start -0.12065 -0.2794)
			(end 0.12065 -0.2794)
			(stroke
				(width 0.1)
				(type default)
			)
			(layer "F.Fab")
		)
		(fp_line
			(start 0.12065 -0.2794)
			(end 0.12065 -0.3048)
			(stroke
				(width 0.1)
				(type default)
			)
			(layer "F.Fab")
		)
		(fp_line
			(start 0.12065 -0.3048)
			(end 0.67945 -0.3048)
			(stroke
				(width 0.1)
				(type default)
			)
			(layer "F.Fab")
		)
		(fp_line
			(start 0.67945 -0.3048)
			(end 0.67945 0.3048)
			(stroke
				(width 0.1)
				(type default)
			)
			(layer "F.Fab")
		)
		(fp_line
			(start -0.67945 -0.305054)
			(end -0.12065 -0.305054)
			(stroke
				(width 0.1)
				(type default)
			)
			(layer "F.Fab")
		)
		(fp_line
			(start -0.12065 -0.305054)
			(end -0.12065 -0.2794)
			(stroke
				(width 0.1)
				(type default)
			)
			(layer "F.Fab")
		)
		(pad "1" smd circle
			(at -0.40005 0 270)
			(size 0 0)
			(layers "F.Cu" "F.Mask" "F.Paste")
			(net "PWRGD_CPU0_PWROK")
		)
		(pad "2" smd circle
			(at 0.40005 0 270)
			(size 0 0)
			(layers "F.Cu" "F.Mask" "F.Paste")
			(net "GND")
		)
	)
	(footprint ""
		(layer "F.Cu")
		(at 405.764746 -142.871952 -90)
		(property "Reference" "C1170"
			(at 0 0 270)
			(layer "F.SilkS")
			(hide yes)
			(effects
				(font
					(size 1.27 1.27)
				)
			)
		)
		(property "Value" ""
			(at 0 0 270)
			(layer "F.Fab")
			(effects
				(font
					(size 1.27 1.27)
				)
			)
		)
		(duplicate_pad_numbers_are_jumpers no)
		(fp_line
			(start -1.524 0.762)
			(end -1.524 -0.762)
			(stroke
				(width 0.1524)
				(type default)
			)
			(layer "F.SilkS")
		)
		(fp_line
			(start 1.524 0.762)
			(end -1.524 0.762)
			(stroke
				(width 0.1524)
				(type default)
			)
			(layer "F.SilkS")
		)
		(fp_line
			(start -1.524 -0.762)
			(end 1.524 -0.762)
			(stroke
				(width 0.1524)
				(type default)
			)
			(layer "F.SilkS")
		)
		(fp_line
			(start 1.524 -0.762)
			(end 1.524 0.762)
			(stroke
				(width 0.1524)
				(type default)
			)
			(layer "F.SilkS")
		)
		(fp_line
			(start -1.1049 0.724916)
			(end 1.1049 0.724916)
			(stroke
				(width 0.1)
				(type default)
			)
			(layer "F.Fab")
		)
		(fp_line
			(start 1.1049 0.724916)
			(end 1.1049 -0.724916)
			(stroke
				(width 0.1)
				(type default)
			)
			(layer "F.Fab")
		)
		(fp_line
			(start -1.1049 -0.724916)
			(end -1.1049 0.724916)
			(stroke
				(width 0.1)
				(type default)
			)
			(layer "F.Fab")
		)
		(fp_line
			(start 1.1049 -0.724916)
			(end -1.1049 -0.724916)
			(stroke
				(width 0.1)
				(type default)
			)
			(layer "F.Fab")
		)
		(pad "1" smd rect
			(at -0.889 0 90)
			(size 1.016 1.27)
			(layers "F.Cu" "F.Mask" "F.Paste")
			(net "P5V_AUX")
		)
		(pad "2" smd rect
			(at 0.889 0 90)
			(size 1.016 1.27)
			(layers "F.Cu" "F.Mask" "F.Paste")
			(net "GND")
		)
	)
	(footprint ""
		(layer "F.Cu")
		(at 115.010946 -53.49748 180)
		(property "Reference" "R6296"
			(at 0 0 180)
			(layer "F.SilkS")
			(hide yes)
			(effects
				(font
					(size 1.27 1.27)
				)
			)
		)
		(property "Value" ""
			(at 0 0 180)
			(layer "F.Fab")
			(effects
				(font
					(size 1.27 1.27)
				)
			)
		)
		(duplicate_pad_numbers_are_jumpers no)
		(fp_line
			(start 0.7874 0.4064)
			(end -0.7874 0.4064)
			(stroke
				(width 0.1524)
				(type default)
			)
			(layer "F.SilkS")
		)
		(fp_line
			(start 0.7874 -0.4064)
			(end 0.7874 0.4064)
			(stroke
				(width 0.1524)
				(type default)
			)
			(layer "F.SilkS")
		)
		(fp_line
			(start -0.7874 0.4064)
			(end -0.7874 -0.4064)
			(stroke
				(width 0.1524)
				(type default)
			)
			(layer "F.SilkS")
		)
		(fp_line
			(start -0.7874 -0.4064)
			(end 0.7874 -0.4064)
			(stroke
				(width 0.1524)
				(type default)
			)
			(layer "F.SilkS")
		)
		(fp_line
			(start 0.67945 0.3048)
			(end 0.120396 0.3048)
			(stroke
				(width 0.1)
				(type default)
			)
			(layer "F.Fab")
		)
		(fp_line
			(start 0.67945 -0.3048)
			(end 0.67945 0.3048)
			(stroke
				(width 0.1)
				(type default)
			)
			(layer "F.Fab")
		)
		(fp_line
			(start 0.12065 -0.2794)
			(end 0.12065 -0.3048)
			(stroke
				(width 0.1)
				(type default)
			)
			(layer "F.Fab")
		)
		(fp_line
			(start 0.12065 -0.3048)
			(end 0.67945 -0.3048)
			(stroke
				(width 0.1)
				(type default)
			)
			(layer "F.Fab")
		)
		(fp_line
			(start 0.120396 0.3048)
			(end 0.120396 0.2794)
			(stroke
				(width 0.1)
				(type default)
			)
			(layer "F.Fab")
		)
		(fp_line
			(start 0.120396 0.2794)
			(end -0.12065 0.2794)
			(stroke
				(width 0.1)
				(type default)
			)
			(layer "F.Fab")
		)
		(fp_line
			(start -0.12065 0.3048)
			(end -0.67945 0.3048)
			(stroke
				(width 0.1)
				(type default)
			)
			(layer "F.Fab")
		)
		(fp_line
			(start -0.12065 0.2794)
			(end -0.12065 0.3048)
			(stroke
				(width 0.1)
				(type default)
			)
			(layer "F.Fab")
		)
		(fp_line
			(start -0.12065 -0.2794)
			(end 0.12065 -0.2794)
			(stroke
				(width 0.1)
				(type default)
			)
			(layer "F.Fab")
		)
		(fp_line
			(start -0.12065 -0.305054)
			(end -0.12065 -0.2794)
			(stroke
				(width 0.1)
				(type default)
			)
			(layer "F.Fab")
		)
		(fp_line
			(start -0.67945 0.3048)
			(end -0.67945 -0.305054)
			(stroke
				(width 0.1)
				(type default)
			)
			(layer "F.Fab")
		)
		(fp_line
			(start -0.67945 -0.305054)
			(end -0.12065 -0.305054)
			(stroke
				(width 0.1)
				(type default)
			)
			(layer "F.Fab")
		)
		(pad "1" smd circle
			(at -0.40005 0 180)
			(size 0 0)
			(layers "F.Cu" "F.Mask" "F.Paste")
			(net "USB_HUB2_MRP_I2C_SLV_CFG1")
		)
		(pad "2" smd circle
			(at 0.40005 0 180)
			(size 0 0)
			(layers "F.Cu" "F.Mask" "F.Paste")
			(net "USB_HUB2_TI_OVERCUR4_MRP_I2C_SLV_CFG1")
		)
	)
	(footprint ""
		(layer "F.Cu")
		(at 200.939908 -108.545376 180)
		(property "Reference" "R209"
			(at 0 0 180)
			(layer "F.SilkS")
			(hide yes)
			(effects
				(font
					(size 1.27 1.27)
				)
			)
		)
		(property "Value" ""
			(at 0 0 180)
			(layer "F.Fab")
			(effects
				(font
					(size 1.27 1.27)
				)
			)
		)
		(duplicate_pad_numbers_are_jumpers no)
		(fp_line
			(start 0.7874 0.4064)
			(end -0.7874 0.4064)
			(stroke
				(width 0.1524)
				(type default)
			)
			(layer "F.SilkS")
		)
		(fp_line
			(start 0.7874 -0.4064)
			(end 0.7874 0.4064)
			(stroke
				(width 0.1524)
				(type default)
			)
			(layer "F.SilkS")
		)
		(fp_line
			(start -0.7874 0.4064)
			(end -0.7874 -0.4064)
			(stroke
				(width 0.1524)
				(type default)
			)
			(layer "F.SilkS")
		)
		(fp_line
			(start -0.7874 -0.4064)
			(end 0.7874 -0.4064)
			(stroke
				(width 0.1524)
				(type default)
			)
			(layer "F.SilkS")
		)
		(fp_line
			(start 0.67945 0.3048)
			(end 0.120396 0.3048)
			(stroke
				(width 0.1)
				(type default)
			)
			(layer "F.Fab")
		)
		(fp_line
			(start 0.67945 -0.3048)
			(end 0.67945 0.3048)
			(stroke
				(width 0.1)
				(type default)
			)
			(layer "F.Fab")
		)
		(fp_line
			(start 0.12065 -0.2794)
			(end 0.12065 -0.3048)
			(stroke
				(width 0.1)
				(type default)
			)
			(layer "F.Fab")
		)
		(fp_line
			(start 0.12065 -0.3048)
			(end 0.67945 -0.3048)
			(stroke
				(width 0.1)
				(type default)
			)
			(layer "F.Fab")
		)
		(fp_line
			(start 0.120396 0.3048)
			(end 0.120396 0.2794)
			(stroke
				(width 0.1)
				(type default)
			)
			(layer "F.Fab")
		)
		(fp_line
			(start 0.120396 0.2794)
			(end -0.12065 0.2794)
			(stroke
				(width 0.1)
				(type default)
			)
			(layer "F.Fab")
		)
		(fp_line
			(start -0.12065 0.3048)
			(end -0.67945 0.3048)
			(stroke
				(width 0.1)
				(type default)
			)
			(layer "F.Fab")
		)
		(fp_line
			(start -0.12065 0.2794)
			(end -0.12065 0.3048)
			(stroke
				(width 0.1)
				(type default)
			)
			(layer "F.Fab")
		)
		(fp_line
			(start -0.12065 -0.2794)
			(end 0.12065 -0.2794)
			(stroke
				(width 0.1)
				(type default)
			)
			(layer "F.Fab")
		)
		(fp_line
			(start -0.12065 -0.305054)
			(end -0.12065 -0.2794)
			(stroke
				(width 0.1)
				(type default)
			)
			(layer "F.Fab")
		)
		(fp_line
			(start -0.67945 0.3048)
			(end -0.67945 -0.305054)
			(stroke
				(width 0.1)
				(type default)
			)
			(layer "F.Fab")
		)
		(fp_line
			(start -0.67945 -0.305054)
			(end -0.12065 -0.305054)
			(stroke
				(width 0.1)
				(type default)
			)
			(layer "F.Fab")
		)
		(pad "1" smd circle
			(at -0.40005 0 180)
			(size 0 0)
			(layers "F.Cu" "F.Mask" "F.Paste")
			(net "PWRGD_PVDDCR_CPU0_P1")
		)
		(pad "2" smd circle
			(at 0.40005 0 180)
			(size 0 0)
			(layers "F.Cu" "F.Mask" "F.Paste")
			(net "FM_PWRGD_PVDDCR_CPU0_P1")
		)
	)
)
